(kicad_pcb
	(version 20260206)
	(generator "pcbnew")
	(generator_version "10.0")
	(general
		(thickness 1.6)
		(legacy_teardrops no)
	)
	(paper "A4")
	(title_block
		(title "01162023_DA0F0TEBIF0_F0T_Expander_BD_F_brd_V02_OCP.brd")
		(comment 1 "Grand Teton / footprints 9685-9692 of 9728")
	)
	(layers
		(0 "F.Cu" signal "TOP")
		(4 "In1.Cu" signal "GND")
		(6 "In2.Cu" signal "VCC")
		(8 "In3.Cu" signal "VCC1")
		(10 "In4.Cu" signal "GND1")
		(12 "In5.Cu" signal "IN1")
		(14 "In6.Cu" signal "GND2")
		(16 "In7.Cu" signal "IN2")
		(18 "In8.Cu" signal "GND3")
		(20 "In9.Cu" signal "IN3")
		(22 "In10.Cu" signal "GND4")
		(24 "In11.Cu" signal "IN4")
		(26 "In12.Cu" signal "GND5")
		(28 "In13.Cu" signal "IN5")
		(30 "In14.Cu" signal "GND6")
		(32 "In15.Cu" signal "IN6")
		(34 "In16.Cu" signal "GND7")
		(2 "B.Cu" signal "BOTTOM")
		(9 "F.Adhes" user "F.Adhesive")
		(11 "B.Adhes" user "B.Adhesive")
		(13 "F.Paste" user "Package Geometry/Pastemask Top")
		(15 "B.Paste" user "Package Geometry/Pastemask Bottom")
		(5 "F.SilkS" user "Ref Des/Silkscreen Top")
		(7 "B.SilkS" user "Ref Des/Silkscreen Bottom")
		(1 "F.Mask" user "Board Geometry/Soldermask Top")
		(3 "B.Mask" user "Board Geometry/Soldermask Bottom")
		(17 "Dwgs.User" user "User.Drawings")
		(19 "Cmts.User" user "User.Comments")
		(21 "Eco1.User" user "User.Eco1")
		(23 "Eco2.User" user "User.Eco2")
		(25 "Edge.Cuts" user "Board Geometry/Outline")
		(27 "Margin" user)
		(31 "F.CrtYd" user "Package Geometry/Place Bound Top")
		(29 "B.CrtYd" user "Package Geometry/Place Bound Bottom")
		(35 "F.Fab" user "Ref Des/Assembly Top")
		(33 "B.Fab" user "Ref Des/Assembly Bottom")
	)
	(footprint ""
		(layer "B.Cu")
		(at 383.667 -235.585 -90)
		(property "Reference" "R908"
			(at 0 0 90)
			(layer "B.SilkS")
			(hide yes)
			(effects
				(font
					(size 1.27 1.27)
				)
				(justify mirror)
			)
		)
		(property "Value" ""
			(at 0 0 90)
			(layer "B.Fab")
			(effects
				(font
					(size 1.27 1.27)
				)
				(justify mirror)
			)
		)
		(duplicate_pad_numbers_are_jumpers no)
		(fp_line
			(start -0.7874 0.4064)
			(end 0.7874 0.4064)
			(stroke
				(width 0.1524)
				(type default)
			)
			(layer "B.SilkS")
		)
		(fp_line
			(start 0.7874 0.4064)
			(end 0.7874 -0.4064)
			(stroke
				(width 0.1524)
				(type default)
			)
			(layer "B.SilkS")
		)
		(fp_line
			(start -0.7874 -0.4064)
			(end -0.7874 0.4064)
			(stroke
				(width 0.1524)
				(type default)
			)
			(layer "B.SilkS")
		)
		(fp_line
			(start 0.7874 -0.4064)
			(end -0.7874 -0.4064)
			(stroke
				(width 0.1524)
				(type default)
			)
			(layer "B.SilkS")
		)
		(fp_line
			(start -0.67945 0.3048)
			(end -0.120396 0.3048)
			(stroke
				(width 0.1)
				(type default)
			)
			(layer "B.Fab")
		)
		(fp_line
			(start -0.120396 0.3048)
			(end -0.120396 0.2794)
			(stroke
				(width 0.1)
				(type default)
			)
			(layer "B.Fab")
		)
		(fp_line
			(start 0.12065 0.3048)
			(end 0.67945 0.3048)
			(stroke
				(width 0.1)
				(type default)
			)
			(layer "B.Fab")
		)
		(fp_line
			(start 0.67945 0.3048)
			(end 0.67945 -0.305054)
			(stroke
				(width 0.1)
				(type default)
			)
			(layer "B.Fab")
		)
		(fp_line
			(start -0.120396 0.2794)
			(end 0.12065 0.2794)
			(stroke
				(width 0.1)
				(type default)
			)
			(layer "B.Fab")
		)
		(fp_line
			(start 0.12065 0.2794)
			(end 0.12065 0.3048)
			(stroke
				(width 0.1)
				(type default)
			)
			(layer "B.Fab")
		)
		(fp_line
			(start -0.12065 -0.2794)
			(end -0.12065 -0.3048)
			(stroke
				(width 0.1)
				(type default)
			)
			(layer "B.Fab")
		)
		(fp_line
			(start 0.12065 -0.2794)
			(end -0.12065 -0.2794)
			(stroke
				(width 0.1)
				(type default)
			)
			(layer "B.Fab")
		)
		(fp_line
			(start -0.67945 -0.3048)
			(end -0.67945 0.3048)
			(stroke
				(width 0.1)
				(type default)
			)
			(layer "B.Fab")
		)
		(fp_line
			(start -0.12065 -0.3048)
			(end -0.67945 -0.3048)
			(stroke
				(width 0.1)
				(type default)
			)
			(layer "B.Fab")
		)
		(fp_line
			(start 0.12065 -0.305054)
			(end 0.12065 -0.2794)
			(stroke
				(width 0.1)
				(type default)
			)
			(layer "B.Fab")
		)
		(fp_line
			(start 0.67945 -0.305054)
			(end 0.12065 -0.305054)
			(stroke
				(width 0.1)
				(type default)
			)
			(layer "B.Fab")
		)
		(pad "1" smd circle
			(at 0.40005 0 90)
			(size 0 0)
			(layers "B.Cu" "B.Mask" "B.Paste")
			(net "FT4232_SDB_REF")
		)
		(pad "2" smd circle
			(at -0.40005 0 90)
			(size 0 0)
			(layers "B.Cu" "B.Mask" "B.Paste")
			(net "GND")
		)
	)
	(footprint ""
		(layer "B.Cu")
		(at 292.32479 -286.399732 90)
		(property "Reference" "C3303"
			(at 0 0 90)
			(layer "B.SilkS")
			(hide yes)
			(effects
				(font
					(size 1.27 1.27)
				)
				(justify mirror)
			)
		)
		(property "Value" ""
			(at 0 0 90)
			(layer "B.Fab")
			(effects
				(font
					(size 1.27 1.27)
				)
				(justify mirror)
			)
		)
		(duplicate_pad_numbers_are_jumpers no)
		(fp_line
			(start 0.299974 -0.150114)
			(end -0.299974 -0.150114)
			(stroke
				(width 0.1)
				(type default)
			)
			(layer "B.Fab")
		)
		(fp_line
			(start -0.299974 -0.150114)
			(end -0.299974 0.150114)
			(stroke
				(width 0.1)
				(type default)
			)
			(layer "B.Fab")
		)
		(fp_line
			(start 0.299974 0.150114)
			(end 0.299974 -0.150114)
			(stroke
				(width 0.1)
				(type default)
			)
			(layer "B.Fab")
		)
		(fp_line
			(start -0.299974 0.150114)
			(end 0.299974 0.150114)
			(stroke
				(width 0.1)
				(type default)
			)
			(layer "B.Fab")
		)
		(pad "1" smd rect
			(at 0.2667 0 270)
			(size 0.3048 0.381)
			(layers "B.Cu" "B.Mask" "B.Paste")
			(net "P1V25_SERDES_VDDPLL_PEX2")
		)
		(pad "2" smd rect
			(at -0.2667 0 270)
			(size 0.3048 0.381)
			(layers "B.Cu" "B.Mask" "B.Paste")
			(net "GND")
		)
	)
	(footprint ""
		(layer "B.Cu")
		(at 252.0188 -354.1268 180)
		(property "Reference" "R6647"
			(at 0 0 0)
			(layer "B.SilkS")
			(hide yes)
			(effects
				(font
					(size 1.27 1.27)
				)
				(justify mirror)
			)
		)
		(property "Value" ""
			(at 0 0 0)
			(layer "B.Fab")
			(effects
				(font
					(size 1.27 1.27)
				)
				(justify mirror)
			)
		)
		(duplicate_pad_numbers_are_jumpers no)
		(fp_line
			(start 0.7874 0.4064)
			(end 0.7874 -0.4064)
			(stroke
				(width 0.1524)
				(type default)
			)
			(layer "B.SilkS")
		)
		(fp_line
			(start 0.7874 -0.4064)
			(end -0.7874 -0.4064)
			(stroke
				(width 0.1524)
				(type default)
			)
			(layer "B.SilkS")
		)
		(fp_line
			(start -0.7874 0.4064)
			(end 0.7874 0.4064)
			(stroke
				(width 0.1524)
				(type default)
			)
			(layer "B.SilkS")
		)
		(fp_line
			(start -0.7874 -0.4064)
			(end -0.7874 0.4064)
			(stroke
				(width 0.1524)
				(type default)
			)
			(layer "B.SilkS")
		)
		(fp_line
			(start 0.67945 0.3048)
			(end 0.67945 -0.305054)
			(stroke
				(width 0.1)
				(type default)
			)
			(layer "B.Fab")
		)
		(fp_line
			(start 0.67945 -0.305054)
			(end 0.12065 -0.305054)
			(stroke
				(width 0.1)
				(type default)
			)
			(layer "B.Fab")
		)
		(fp_line
			(start 0.12065 0.3048)
			(end 0.67945 0.3048)
			(stroke
				(width 0.1)
				(type default)
			)
			(layer "B.Fab")
		)
		(fp_line
			(start 0.12065 0.2794)
			(end 0.12065 0.3048)
			(stroke
				(width 0.1)
				(type default)
			)
			(layer "B.Fab")
		)
		(fp_line
			(start 0.12065 -0.2794)
			(end -0.12065 -0.2794)
			(stroke
				(width 0.1)
				(type default)
			)
			(layer "B.Fab")
		)
		(fp_line
			(start 0.12065 -0.305054)
			(end 0.12065 -0.2794)
			(stroke
				(width 0.1)
				(type default)
			)
			(layer "B.Fab")
		)
		(fp_line
			(start -0.120396 0.3048)
			(end -0.120396 0.2794)
			(stroke
				(width 0.1)
				(type default)
			)
			(layer "B.Fab")
		)
		(fp_line
			(start -0.120396 0.2794)
			(end 0.12065 0.2794)
			(stroke
				(width 0.1)
				(type default)
			)
			(layer "B.Fab")
		)
		(fp_line
			(start -0.12065 -0.2794)
			(end -0.12065 -0.3048)
			(stroke
				(width 0.1)
				(type default)
			)
			(layer "B.Fab")
		)
		(fp_line
			(start -0.12065 -0.3048)
			(end -0.67945 -0.3048)
			(stroke
				(width 0.1)
				(type default)
			)
			(layer "B.Fab")
		)
		(fp_line
			(start -0.67945 0.3048)
			(end -0.120396 0.3048)
			(stroke
				(width 0.1)
				(type default)
			)
			(layer "B.Fab")
		)
		(fp_line
			(start -0.67945 -0.3048)
			(end -0.67945 0.3048)
			(stroke
				(width 0.1)
				(type default)
			)
			(layer "B.Fab")
		)
		(pad "1" smd circle
			(at 0.40005 0)
			(size 0 0)
			(layers "B.Cu" "B.Mask" "B.Paste")
			(net "HSC_CSOUT")
		)
		(pad "2" smd circle
			(at -0.40005 0)
			(size 0 0)
			(layers "B.Cu" "B.Mask" "B.Paste")
			(net "HSC_D_OC_BUF_R_N")
		)
	)
	(footprint ""
		(layer "B.Cu")
		(at 342.093804 -218.787218 -90)
		(property "Reference" "C2066"
			(at 0 0 90)
			(layer "B.SilkS")
			(hide yes)
			(effects
				(font
					(size 1.27 1.27)
				)
				(justify mirror)
			)
		)
		(property "Value" ""
			(at 0 0 90)
			(layer "B.Fab")
			(effects
				(font
					(size 1.27 1.27)
				)
				(justify mirror)
			)
		)
		(duplicate_pad_numbers_are_jumpers no)
		(fp_line
			(start -0.69215 0.2921)
			(end 0.69215 0.2921)
			(stroke
				(width 0.1524)
				(type default)
			)
			(layer "B.SilkS")
		)
		(fp_line
			(start 0.69215 0.2921)
			(end 0.69215 -0.2921)
			(stroke
				(width 0.1524)
				(type default)
			)
			(layer "B.SilkS")
		)
		(fp_line
			(start -0.69215 -0.2921)
			(end -0.69215 0.2921)
			(stroke
				(width 0.1524)
				(type default)
			)
			(layer "B.SilkS")
		)
		(fp_line
			(start 0.69215 -0.2921)
			(end -0.69215 -0.2921)
			(stroke
				(width 0.1524)
				(type default)
			)
			(layer "B.SilkS")
		)
		(fp_line
			(start -0.51435 0.2794)
			(end 0.51435 0.2794)
			(stroke
				(width 0.1)
				(type default)
			)
			(layer "B.Fab")
		)
		(fp_line
			(start 0.51435 0.2794)
			(end 0.51435 -0.2794)
			(stroke
				(width 0.1)
				(type default)
			)
			(layer "B.Fab")
		)
		(fp_line
			(start -0.51435 -0.2794)
			(end -0.51435 0.2794)
			(stroke
				(width 0.1)
				(type default)
			)
			(layer "B.Fab")
		)
		(fp_line
			(start 0.51435 -0.2794)
			(end -0.51435 -0.2794)
			(stroke
				(width 0.1)
				(type default)
			)
			(layer "B.Fab")
		)
		(pad "1" smd circle
			(at 0.40005 0 90)
			(size 0 0)
			(layers "B.Cu" "B.Mask" "B.Paste")
			(net "P3V3_VCC_FPGA_CORE")
		)
		(pad "2" smd circle
			(at -0.40005 0 90)
			(size 0 0)
			(layers "B.Cu" "B.Mask" "B.Paste")
			(net "GND")
		)
		(zone
			(layer "B.Cu")
			(hatch none 0.5)
			(connect_pads
				(clearance 0)
			)
			(min_thickness 0.25)
			(keepout
				(tracks not_allowed)
				(vias allowed)
				(pads allowed)
				(copperpour not_allowed)
				(footprints allowed)
			)
			(placement
				(enabled no)
				(sheetname "")
			)
			(fill
				(thermal_gap 0.5)
				(thermal_bridge_width 0.5)
				(island_removal_mode 0)
			)
			(polygon
				(pts
					(xy 342.006174 -218.596718) (xy 341.948008 -218.688158) (xy 341.948008 -218.887548) (xy 342.006174 -218.977718)
					(xy 342.181434 -218.977718) (xy 342.239854 -218.887548) (xy 342.239854 -218.688158) (xy 342.181688 -218.596718)
				)
			)
		)
	)
	(footprint ""
		(layer "B.Cu")
		(at 350.153986 -260.39572 -90)
		(property "Reference" "PR139"
			(at 0 0 90)
			(layer "B.SilkS")
			(hide yes)
			(effects
				(font
					(size 1.27 1.27)
				)
				(justify mirror)
			)
		)
		(property "Value" ""
			(at 0 0 90)
			(layer "B.Fab")
			(effects
				(font
					(size 1.27 1.27)
				)
				(justify mirror)
			)
		)
		(duplicate_pad_numbers_are_jumpers no)
		(fp_line
			(start -0.7874 0.4064)
			(end 0.7874 0.4064)
			(stroke
				(width 0.1524)
				(type default)
			)
			(layer "B.SilkS")
		)
		(fp_line
			(start 0.7874 0.4064)
			(end 0.7874 -0.4064)
			(stroke
				(width 0.1524)
				(type default)
			)
			(layer "B.SilkS")
		)
		(fp_line
			(start -0.7874 -0.4064)
			(end -0.7874 0.4064)
			(stroke
				(width 0.1524)
				(type default)
			)
			(layer "B.SilkS")
		)
		(fp_line
			(start 0.7874 -0.4064)
			(end -0.7874 -0.4064)
			(stroke
				(width 0.1524)
				(type default)
			)
			(layer "B.SilkS")
		)
		(fp_line
			(start -0.67945 0.3048)
			(end -0.120396 0.3048)
			(stroke
				(width 0.1)
				(type default)
			)
			(layer "B.Fab")
		)
		(fp_line
			(start -0.120396 0.3048)
			(end -0.120396 0.2794)
			(stroke
				(width 0.1)
				(type default)
			)
			(layer "B.Fab")
		)
		(fp_line
			(start 0.12065 0.3048)
			(end 0.67945 0.3048)
			(stroke
				(width 0.1)
				(type default)
			)
			(layer "B.Fab")
		)
		(fp_line
			(start 0.67945 0.3048)
			(end 0.67945 -0.305054)
			(stroke
				(width 0.1)
				(type default)
			)
			(layer "B.Fab")
		)
		(fp_line
			(start -0.120396 0.2794)
			(end 0.12065 0.2794)
			(stroke
				(width 0.1)
				(type default)
			)
			(layer "B.Fab")
		)
		(fp_line
			(start 0.12065 0.2794)
			(end 0.12065 0.3048)
			(stroke
				(width 0.1)
				(type default)
			)
			(layer "B.Fab")
		)
		(fp_line
			(start -0.12065 -0.2794)
			(end -0.12065 -0.3048)
			(stroke
				(width 0.1)
				(type default)
			)
			(layer "B.Fab")
		)
		(fp_line
			(start 0.12065 -0.2794)
			(end -0.12065 -0.2794)
			(stroke
				(width 0.1)
				(type default)
			)
			(layer "B.Fab")
		)
		(fp_line
			(start -0.67945 -0.3048)
			(end -0.67945 0.3048)
			(stroke
				(width 0.1)
				(type default)
			)
			(layer "B.Fab")
		)
		(fp_line
			(start -0.12065 -0.3048)
			(end -0.67945 -0.3048)
			(stroke
				(width 0.1)
				(type default)
			)
			(layer "B.Fab")
		)
		(fp_line
			(start 0.12065 -0.305054)
			(end 0.12065 -0.2794)
			(stroke
				(width 0.1)
				(type default)
			)
			(layer "B.Fab")
		)
		(fp_line
			(start 0.67945 -0.305054)
			(end 0.12065 -0.305054)
			(stroke
				(width 0.1)
				(type default)
			)
			(layer "B.Fab")
		)
		(pad "1" smd circle
			(at 0.40005 0 90)
			(size 0 0)
			(layers "B.Cu" "B.Mask" "B.Paste")
			(net "P0V8_PEX3_TSEN_R")
		)
		(pad "2" smd circle
			(at -0.40005 0 90)
			(size 0 0)
			(layers "B.Cu" "B.Mask" "B.Paste")
			(net "P0V8_PEX3_TSEN")
		)
	)
	(footprint ""
		(layer "B.Cu")
		(at 236.234732 -290.501832)
		(property "Reference" "PC997"
			(at 0 0 0)
			(layer "B.SilkS")
			(hide yes)
			(effects
				(font
					(size 1.27 1.27)
				)
				(justify mirror)
			)
		)
		(property "Value" ""
			(at 0 0 0)
			(layer "B.Fab")
			(effects
				(font
					(size 1.27 1.27)
				)
				(justify mirror)
			)
		)
		(duplicate_pad_numbers_are_jumpers no)
		(fp_line
			(start -1.524 -0.762)
			(end -1.524 0.762)
			(stroke
				(width 0.1524)
				(type default)
			)
			(layer "B.SilkS")
		)
		(fp_line
			(start -1.524 0.762)
			(end 1.524 0.762)
			(stroke
				(width 0.1524)
				(type default)
			)
			(layer "B.SilkS")
		)
		(fp_line
			(start 1.524 -0.762)
			(end -1.524 -0.762)
			(stroke
				(width 0.1524)
				(type default)
			)
			(layer "B.SilkS")
		)
		(fp_line
			(start 1.524 0.762)
			(end 1.524 -0.762)
			(stroke
				(width 0.1524)
				(type default)
			)
			(layer "B.SilkS")
		)
		(fp_line
			(start -1.1049 -0.724916)
			(end 1.1049 -0.724916)
			(stroke
				(width 0.1)
				(type default)
			)
			(layer "B.Fab")
		)
		(fp_line
			(start -1.1049 0.724916)
			(end -1.1049 -0.724916)
			(stroke
				(width 0.1)
				(type default)
			)
			(layer "B.Fab")
		)
		(fp_line
			(start 1.1049 -0.724916)
			(end 1.1049 0.724916)
			(stroke
				(width 0.1)
				(type default)
			)
			(layer "B.Fab")
		)
		(fp_line
			(start 1.1049 0.724916)
			(end -1.1049 0.724916)
			(stroke
				(width 0.1)
				(type default)
			)
			(layer "B.Fab")
		)
		(pad "1" smd rect
			(at 0.889 0)
			(size 1.016 1.27)
			(layers "B.Cu" "B.Mask" "B.Paste")
			(net "P1V25_PEX2_R")
		)
		(pad "2" smd rect
			(at -0.889 0)
			(size 1.016 1.27)
			(layers "B.Cu" "B.Mask" "B.Paste")
			(net "GND")
		)
	)
	(footprint ""
		(layer "B.Cu")
		(at 345.29395 -217.187018 -90)
		(property "Reference" "C2045"
			(at 0 0 90)
			(layer "B.SilkS")
			(hide yes)
			(effects
				(font
					(size 1.27 1.27)
				)
				(justify mirror)
			)
		)
		(property "Value" ""
			(at 0 0 90)
			(layer "B.Fab")
			(effects
				(font
					(size 1.27 1.27)
				)
				(justify mirror)
			)
		)
		(duplicate_pad_numbers_are_jumpers no)
		(fp_line
			(start -0.69215 0.2921)
			(end 0.69215 0.2921)
			(stroke
				(width 0.1524)
				(type default)
			)
			(layer "B.SilkS")
		)
		(fp_line
			(start 0.69215 0.2921)
			(end 0.69215 -0.2921)
			(stroke
				(width 0.1524)
				(type default)
			)
			(layer "B.SilkS")
		)
		(fp_line
			(start -0.69215 -0.2921)
			(end -0.69215 0.2921)
			(stroke
				(width 0.1524)
				(type default)
			)
			(layer "B.SilkS")
		)
		(fp_line
			(start 0.69215 -0.2921)
			(end -0.69215 -0.2921)
			(stroke
				(width 0.1524)
				(type default)
			)
			(layer "B.SilkS")
		)
		(fp_line
			(start -0.51435 0.2794)
			(end 0.51435 0.2794)
			(stroke
				(width 0.1)
				(type default)
			)
			(layer "B.Fab")
		)
		(fp_line
			(start 0.51435 0.2794)
			(end 0.51435 -0.2794)
			(stroke
				(width 0.1)
				(type default)
			)
			(layer "B.Fab")
		)
		(fp_line
			(start -0.51435 -0.2794)
			(end -0.51435 0.2794)
			(stroke
				(width 0.1)
				(type default)
			)
			(layer "B.Fab")
		)
		(fp_line
			(start 0.51435 -0.2794)
			(end -0.51435 -0.2794)
			(stroke
				(width 0.1)
				(type default)
			)
			(layer "B.Fab")
		)
		(pad "1" smd circle
			(at 0.40005 0 90)
			(size 0 0)
			(layers "B.Cu" "B.Mask" "B.Paste")
			(net "P3V3_FPGA_VCCIO1")
		)
		(pad "2" smd circle
			(at -0.40005 0 90)
			(size 0 0)
			(layers "B.Cu" "B.Mask" "B.Paste")
			(net "GND")
		)
		(zone
			(layer "B.Cu")
			(hatch none 0.5)
			(connect_pads
				(clearance 0)
			)
			(min_thickness 0.25)
			(keepout
				(tracks not_allowed)
				(vias allowed)
				(pads allowed)
				(copperpour not_allowed)
				(footprints allowed)
			)
			(placement
				(enabled no)
				(sheetname "")
			)
			(fill
				(thermal_gap 0.5)
				(thermal_bridge_width 0.5)
				(island_removal_mode 0)
			)
			(polygon
				(pts
					(xy 345.20632 -216.996518) (xy 345.148154 -217.087958) (xy 345.148154 -217.287348) (xy 345.20632 -217.377518)
					(xy 345.38158 -217.377518) (xy 345.44 -217.287348) (xy 345.44 -217.087958) (xy 345.381834 -216.996518)
				)
			)
		)
	)
	(footprint ""
		(layer "B.Cu")
		(at 100.90023 -324.178422 180)
		(property "Reference" "PJ19"
			(at 0 0 0)
			(layer "B.SilkS")
			(hide yes)
			(effects
				(font
					(size 1.27 1.27)
				)
				(justify mirror)
			)
		)
		(property "Value" ""
			(at 0 0 0)
			(layer "B.Fab")
			(effects
				(font
					(size 1.27 1.27)
				)
				(justify mirror)
			)
		)
		(duplicate_pad_numbers_are_jumpers no)
		(pad "1" smd circle
			(at 0.40005 0 270)
			(size 0 0)
			(layers "B.Cu" "B.Mask" "B.Paste")
			(net "VSENSE_P0V8_PEX0_SKT_VRTN")
		)
		(pad "2" smd rect
			(at -0.40005 0 180)
			(size 0.4572 0.508)
			(layers "B.Cu" "B.Mask" "B.Paste")
			(net "SH_P0V8_PEX0_RGND0")
		)
		(zone
			(layer "B.Cu")
			(hatch none 0.5)
			(connect_pads
				(clearance 0)
			)
			(min_thickness 0.25)
			(keepout
				(tracks allowed)
				(vias not_allowed)
				(pads allowed)
				(copperpour not_allowed)
				(footprints allowed)
			)
			(placement
				(enabled no)
				(sheetname "")
			)
			(fill
				(thermal_gap 0.5)
				(thermal_bridge_width 0.5)
				(island_removal_mode 0)
			)
			(polygon
				(pts
					(xy 101.58603 -324.483222) (xy 101.58603 -323.873622) (xy 100.21443 -323.873622) (xy 100.21443 -324.483222)
				)
			)
		)
	)
)
